(kicad_pcb
	(version 20260206)
	(generator "pcbnew")
	(generator_version "10.0")
	(general
		(thickness 1.6)
		(legacy_teardrops no)
	)
	(paper "A4")
	(title_block
		(title "04192023_DAF0TMB3IC0_F0TG_MB_C_brd_V02_OCP.brd")
		(comment 1 "Grand Teton / footprint 2783 of 8354 (U26), pads 1314-1426 of 6102")
	)
	(layers
		(0 "F.Cu" signal "TOP")
		(4 "In1.Cu" signal "GND")
		(6 "In2.Cu" signal "IN1")
		(8 "In3.Cu" signal "GND1")
		(10 "In4.Cu" signal "IN2")
		(12 "In5.Cu" signal "GND2")
		(14 "In6.Cu" signal "IN3")
		(16 "In7.Cu" signal "GND3")
		(18 "In8.Cu" signal "VCC")
		(20 "In9.Cu" signal "VCC1")
		(22 "In10.Cu" signal "GND4")
		(24 "In11.Cu" signal "IN4")
		(26 "In12.Cu" signal "GND5")
		(28 "In13.Cu" signal "IN5")
		(30 "In14.Cu" signal "GND6")
		(32 "In15.Cu" signal "IN6")
		(34 "In16.Cu" signal "GND7")
		(2 "B.Cu" signal "BOTTOM")
		(9 "F.Adhes" user "F.Adhesive")
		(11 "B.Adhes" user "B.Adhesive")
		(13 "F.Paste" user "Package Geometry/Pastemask Top")
		(15 "B.Paste" user "Package Geometry/Pastemask Bottom")
		(5 "F.SilkS" user "Ref Des/Silkscreen Top")
		(7 "B.SilkS" user "Ref Des/Silkscreen Bottom")
		(1 "F.Mask" user "Board Geometry/Soldermask Top")
		(3 "B.Mask" user "Board Geometry/Soldermask Bottom")
		(17 "Dwgs.User" user "User.Drawings")
		(19 "Cmts.User" user "User.Comments")
		(21 "Eco1.User" user "User.Eco1")
		(23 "Eco2.User" user "User.Eco2")
		(25 "Edge.Cuts" user "Board Geometry/Outline")
		(27 "Margin" user)
		(31 "F.CrtYd" user "Package Geometry/Place Bound Top")
		(29 "B.CrtYd" user "Package Geometry/Place Bound Bottom")
		(35 "F.Fab" user "Ref Des/Assembly Top")
		(33 "B.Fab" user "Ref Des/Assembly Bottom")
	)
	(footprint ""
		(layer "F.Cu")
		(at 111.927894 -258.880356 180)
		(property "Reference" "U26"
			(at -45.05579 -61.794136 0)
			(unlocked yes)
			(layer "F.SilkS")
			(effects
				(font
					(size 0.7874 0.5842)
					(thickness 0.1524)
				)
			)
		)
		(property "Value" ""
			(at 0 0 180)
			(layer "F.Fab")
			(effects
				(font
					(size 1.27 1.27)
				)
			)
		)
		(duplicate_pad_numbers_are_jumpers no)
		(pad "AV29" smd circle
			(at -8.310118 -6.839966 180)
			(size 0.450088 0.450088)
			(layers "F.Cu" "F.Mask" "F.Paste")
			(net "GND")
		)
		(pad "AV30" smd circle
			(at -7.370064 -6.839966 180)
			(size 0.450088 0.450088)
			(layers "F.Cu" "F.Mask" "F.Paste")
			(net "PVDDCR_SOC_P1")
		)
		(pad "AV31" smd circle
			(at -6.43001 -6.839966 180)
			(size 0.450088 0.450088)
			(layers "F.Cu" "F.Mask" "F.Paste")
			(net "GND")
		)
		(pad "AV32" smd circle
			(at -5.489956 -6.839966 180)
			(size 0.450088 0.450088)
			(layers "F.Cu" "F.Mask" "F.Paste")
			(net "PVDDCR_SOC_P1")
		)
		(pad "AV33" smd circle
			(at -4.549902 -6.839966 180)
			(size 0.450088 0.450088)
			(layers "F.Cu" "F.Mask" "F.Paste")
			(net "GND")
		)
		(pad "AV34" smd circle
			(at -3.610102 -6.839966 180)
			(size 0.450088 0.450088)
			(layers "F.Cu" "F.Mask" "F.Paste")
			(net "PVDDCR_SOC_P1")
		)
		(pad "AV35" smd circle
			(at -2.670048 -6.839966 180)
			(size 0.450088 0.450088)
			(layers "F.Cu" "F.Mask" "F.Paste")
			(net "GND")
		)
		(pad "AV36" smd circle
			(at -1.729994 -6.839966 180)
			(size 0.450088 0.450088)
			(layers "F.Cu" "F.Mask" "F.Paste")
			(net "PVDDCR_SOC_P1")
		)
		(pad "AV37" smd circle
			(at -0.78994 -6.839966 180)
			(size 0.450088 0.450088)
			(layers "F.Cu" "F.Mask" "F.Paste")
			(net "GND")
		)
		(pad "AV39" smd circle
			(at 1.089914 -6.839966 180)
			(size 0.450088 0.450088)
			(layers "F.Cu" "F.Mask" "F.Paste")
			(net "PVDDCR_SOC_P1")
		)
		(pad "AV40" smd circle
			(at 2.029968 -6.839966 180)
			(size 0.450088 0.450088)
			(layers "F.Cu" "F.Mask" "F.Paste")
			(net "GND")
		)
		(pad "AV41" smd circle
			(at 2.970022 -6.839966 180)
			(size 0.450088 0.450088)
			(layers "F.Cu" "F.Mask" "F.Paste")
			(net "PVDDCR_SOC_P1")
		)
		(pad "AV42" smd circle
			(at 3.910076 -6.839966 180)
			(size 0.450088 0.450088)
			(layers "F.Cu" "F.Mask" "F.Paste")
			(net "GND")
		)
		(pad "AV43" smd circle
			(at 4.849876 -6.839966 180)
			(size 0.450088 0.450088)
			(layers "F.Cu" "F.Mask" "F.Paste")
			(net "PVDDCR_SOC_P1")
		)
		(pad "AV44" smd circle
			(at 5.78993 -6.839966 180)
			(size 0.450088 0.450088)
			(layers "F.Cu" "F.Mask" "F.Paste")
			(net "GND")
		)
		(pad "AV45" smd circle
			(at 6.729984 -6.839966 180)
			(size 0.450088 0.450088)
			(layers "F.Cu" "F.Mask" "F.Paste")
			(net "PVDDCR_SOC_P1")
		)
		(pad "AV46" smd circle
			(at 7.670038 -6.839966 180)
			(size 0.450088 0.450088)
			(layers "F.Cu" "F.Mask" "F.Paste")
			(net "GND")
		)
		(pad "AV47" smd circle
			(at 8.610092 -6.839966 180)
			(size 0.450088 0.450088)
			(layers "F.Cu" "F.Mask" "F.Paste")
			(net "PVDDCR_SOC_P1")
		)
		(pad "AV48" smd circle
			(at 9.549892 -6.839966 180)
			(size 0.450088 0.450088)
			(layers "F.Cu" "F.Mask" "F.Paste")
			(net "GND")
		)
		(pad "AV49" smd circle
			(at 10.489946 -6.839966 180)
			(size 0.450088 0.450088)
			(layers "F.Cu" "F.Mask" "F.Paste")
			(net "PVDD18_S5_P1")
		)
		(pad "AV50" smd circle
			(at 11.43 -6.839966 180)
			(size 0.450088 0.450088)
			(layers "F.Cu" "F.Mask" "F.Paste")
			(net "GND")
		)
		(pad "AV51" smd circle
			(at 12.370054 -6.839966 180)
			(size 0.450088 0.450088)
			(layers "F.Cu" "F.Mask" "F.Paste")
			(net "PVDD18_S5_P1")
		)
		(pad "AV52" smd circle
			(at 13.310108 -6.839966 180)
			(size 0.450088 0.450088)
			(layers "F.Cu" "F.Mask" "F.Paste")
			(net "GND")
		)
		(pad "AV53" smd circle
			(at 14.249908 -6.839966 180)
			(size 0.450088 0.450088)
			(layers "F.Cu" "F.Mask" "F.Paste")
			(net "PVDD18_S5_P1")
		)
		(pad "AV54" smd circle
			(at 15.189962 -6.839966 180)
			(size 0.450088 0.450088)
			(layers "F.Cu" "F.Mask" "F.Paste")
			(net "GND")
		)
		(pad "AV55" smd circle
			(at 16.130016 -6.839966 180)
			(size 0.450088 0.450088)
			(layers "F.Cu" "F.Mask" "F.Paste")
			(net "Net_2009")
		)
		(pad "AV56" smd circle
			(at 17.07007 -6.839966 180)
			(size 0.450088 0.450088)
			(layers "F.Cu" "F.Mask" "F.Paste")
			(net "M_C_CPU1_SA_CS_N<0>")
		)
		(pad "AV57" smd circle
			(at 18.010124 -6.839966 180)
			(size 0.450088 0.450088)
			(layers "F.Cu" "F.Mask" "F.Paste")
			(net "PVDDIO_P1")
		)
		(pad "AV58" smd circle
			(at 18.949924 -6.839966 180)
			(size 0.450088 0.450088)
			(layers "F.Cu" "F.Mask" "F.Paste")
			(net "Net_2017")
		)
		(pad "AV59" smd circle
			(at 19.889978 -6.839966 180)
			(size 0.450088 0.450088)
			(layers "F.Cu" "F.Mask" "F.Paste")
			(net "GND")
		)
		(pad "AV60" smd circle
			(at 20.830032 -6.839966 180)
			(size 0.450088 0.450088)
			(layers "F.Cu" "F.Mask" "F.Paste")
			(net "M_D_CPU1_SA_CS_N<0>")
		)
		(pad "AV61" smd circle
			(at 21.770086 -6.839966 180)
			(size 0.450088 0.450088)
			(layers "F.Cu" "F.Mask" "F.Paste")
			(net "GND")
		)
		(pad "AV62" smd circle
			(at 22.709886 -6.839966 180)
			(size 0.450088 0.450088)
			(layers "F.Cu" "F.Mask" "F.Paste")
			(net "Net_2001")
		)
		(pad "AV63" smd circle
			(at 23.64994 -6.839966 180)
			(size 0.450088 0.450088)
			(layers "F.Cu" "F.Mask" "F.Paste")
			(net "M_B_CPU1_SA_CS_N<0>")
		)
		(pad "AV64" smd circle
			(at 24.589994 -6.839966 180)
			(size 0.450088 0.450088)
			(layers "F.Cu" "F.Mask" "F.Paste")
			(net "PVDDIO_P1")
		)
		(pad "AV65" smd circle
			(at 25.530048 -6.839966 180)
			(size 0.450088 0.450088)
			(layers "F.Cu" "F.Mask" "F.Paste")
			(net "Net_2033")
		)
		(pad "AV66" smd circle
			(at 26.470102 -6.839966 180)
			(size 0.450088 0.450088)
			(layers "F.Cu" "F.Mask" "F.Paste")
			(net "GND")
		)
		(pad "AV67" smd circle
			(at 27.409902 -6.839966 180)
			(size 0.450088 0.450088)
			(layers "F.Cu" "F.Mask" "F.Paste")
			(net "M_F_CPU1_SA_CS_N<0>")
		)
		(pad "AV68" smd circle
			(at 28.349956 -6.839966 180)
			(size 0.450088 0.450088)
			(layers "F.Cu" "F.Mask" "F.Paste")
			(net "GND")
		)
		(pad "AV69" smd circle
			(at 29.29001 -6.839966 180)
			(size 0.450088 0.450088)
			(layers "F.Cu" "F.Mask" "F.Paste")
			(net "Net_2025")
		)
		(pad "AV70" smd circle
			(at 30.230064 -6.839966 180)
			(size 0.450088 0.450088)
			(layers "F.Cu" "F.Mask" "F.Paste")
			(net "M_E_CPU1_SA_CS_N<0>")
		)
		(pad "AV71" smd circle
			(at 31.170118 -6.839966 180)
			(size 0.450088 0.450088)
			(layers "F.Cu" "F.Mask" "F.Paste")
			(net "PVDDIO_P1")
		)
		(pad "AV72" smd circle
			(at 32.109918 -6.839966 180)
			(size 0.450088 0.450088)
			(layers "F.Cu" "F.Mask" "F.Paste")
			(net "Net_1993")
		)
		(pad "AV73" smd circle
			(at 33.049972 -6.839966 180)
			(size 0.450088 0.450088)
			(layers "F.Cu" "F.Mask" "F.Paste")
			(net "GND")
		)
		(pad "AV74" smd circle
			(at 33.990026 -6.839966 180)
			(size 0.450088 0.450088)
			(layers "F.Cu" "F.Mask" "F.Paste")
			(net "M_A_CPU1_SA_CS_N<0>")
		)
		(pad "AW1" smd circle
			(at -34.159952 -6.02996 180)
			(size 0.450088 0.450088)
			(layers "F.Cu" "F.Mask" "F.Paste")
			(net "GND")
		)
		(pad "AW2" smd circle
			(at -33.219898 -6.02996 180)
			(size 0.450088 0.450088)
			(layers "F.Cu" "F.Mask" "F.Paste")
			(net "M_G_CPU1_SA_CA<0>")
		)
		(pad "AW3" smd circle
			(at -32.280098 -6.02996 180)
			(size 0.450088 0.450088)
			(layers "F.Cu" "F.Mask" "F.Paste")
			(net "Net_2041")
		)
		(pad "AW4" smd circle
			(at -31.340044 -6.02996 180)
			(size 0.450088 0.450088)
			(layers "F.Cu" "F.Mask" "F.Paste")
			(net "GND")
		)
		(pad "AW5" smd circle
			(at -30.39999 -6.02996 180)
			(size 0.450088 0.450088)
			(layers "F.Cu" "F.Mask" "F.Paste")
			(net "M_K_CPU1_SA_CA<0>")
		)
		(pad "AW6" smd circle
			(at -29.459936 -6.02996 180)
			(size 0.450088 0.450088)
			(layers "F.Cu" "F.Mask" "F.Paste")
			(net "GND")
		)
		(pad "AW7" smd circle
			(at -28.519882 -6.02996 180)
			(size 0.450088 0.450088)
			(layers "F.Cu" "F.Mask" "F.Paste")
			(net "Net_2190")
		)
		(pad "AW8" smd circle
			(at -27.580082 -6.02996 180)
			(size 0.450088 0.450088)
			(layers "F.Cu" "F.Mask" "F.Paste")
			(net "GND")
		)
		(pad "AW9" smd circle
			(at -26.640028 -6.02996 180)
			(size 0.450088 0.450088)
			(layers "F.Cu" "F.Mask" "F.Paste")
			(net "M_L_CPU1_SA_CA<0>")
		)
		(pad "AW10" smd circle
			(at -25.699974 -6.02996 180)
			(size 0.450088 0.450088)
			(layers "F.Cu" "F.Mask" "F.Paste")
			(net "Net_2182")
		)
		(pad "AW11" smd circle
			(at -24.75992 -6.02996 180)
			(size 0.450088 0.450088)
			(layers "F.Cu" "F.Mask" "F.Paste")
			(net "GND")
		)
		(pad "AW12" smd circle
			(at -23.82012 -6.02996 180)
			(size 0.450088 0.450088)
			(layers "F.Cu" "F.Mask" "F.Paste")
			(net "M_H_CPU1_SA_CA<0>")
		)
		(pad "AW13" smd circle
			(at -22.880066 -6.02996 180)
			(size 0.450088 0.450088)
			(layers "F.Cu" "F.Mask" "F.Paste")
			(net "GND")
		)
		(pad "AW14" smd circle
			(at -21.940012 -6.02996 180)
			(size 0.450088 0.450088)
			(layers "F.Cu" "F.Mask" "F.Paste")
			(net "Net_2049")
		)
		(pad "AW15" smd circle
			(at -20.999958 -6.02996 180)
			(size 0.450088 0.450088)
			(layers "F.Cu" "F.Mask" "F.Paste")
			(net "GND")
		)
		(pad "AW16" smd circle
			(at -20.059904 -6.02996 180)
			(size 0.450088 0.450088)
			(layers "F.Cu" "F.Mask" "F.Paste")
			(net "M_J_CPU1_SA_CA<0>")
		)
		(pad "AW17" smd circle
			(at -19.120104 -6.02996 180)
			(size 0.450088 0.450088)
			(layers "F.Cu" "F.Mask" "F.Paste")
			(net "Net_2065")
		)
		(pad "AW18" smd circle
			(at -18.18005 -6.02996 180)
			(size 0.450088 0.450088)
			(layers "F.Cu" "F.Mask" "F.Paste")
			(net "GND")
		)
		(pad "AW19" smd circle
			(at -17.239996 -6.02996 180)
			(size 0.450088 0.450088)
			(layers "F.Cu" "F.Mask" "F.Paste")
			(net "M_I_CPU1_SA_CA<0>")
		)
		(pad "AW20" smd circle
			(at -16.299942 -6.02996 180)
			(size 0.450088 0.450088)
			(layers "F.Cu" "F.Mask" "F.Paste")
			(net "GND")
		)
		(pad "AW21" smd circle
			(at -15.359888 -6.02996 180)
			(size 0.450088 0.450088)
			(layers "F.Cu" "F.Mask" "F.Paste")
			(net "Net_2057")
		)
		(pad "AW22" smd circle
			(at -14.420088 -6.02996 180)
			(size 0.450088 0.450088)
			(layers "F.Cu" "F.Mask" "F.Paste")
			(net "GND")
		)
		(pad "AW23" smd circle
			(at -13.480034 -6.02996 180)
			(size 0.450088 0.450088)
			(layers "F.Cu" "F.Mask" "F.Paste")
			(net "PVDDCR_SOC_P1")
		)
		(pad "AW24" smd circle
			(at -12.53998 -6.02996 180)
			(size 0.450088 0.450088)
			(layers "F.Cu" "F.Mask" "F.Paste")
			(net "GND")
		)
		(pad "AW25" smd circle
			(at -11.599926 -6.02996 180)
			(size 0.450088 0.450088)
			(layers "F.Cu" "F.Mask" "F.Paste")
			(net "PVDDCR_SOC_P1")
		)
		(pad "AW26" smd circle
			(at -10.659872 -6.02996 180)
			(size 0.450088 0.450088)
			(layers "F.Cu" "F.Mask" "F.Paste")
			(net "GND")
		)
		(pad "AW27" smd circle
			(at -9.720072 -6.02996 180)
			(size 0.450088 0.450088)
			(layers "F.Cu" "F.Mask" "F.Paste")
			(net "PVDDCR_SOC_P1")
		)
		(pad "AW28" smd circle
			(at -8.780018 -6.02996 180)
			(size 0.450088 0.450088)
			(layers "F.Cu" "F.Mask" "F.Paste")
			(net "GND")
		)
		(pad "AW48" smd circle
			(at 9.079992 -6.02996 180)
			(size 0.450088 0.450088)
			(layers "F.Cu" "F.Mask" "F.Paste")
			(net "PVDDCR_SOC_P1")
		)
		(pad "AW49" smd circle
			(at 10.020046 -6.02996 180)
			(size 0.450088 0.450088)
			(layers "F.Cu" "F.Mask" "F.Paste")
			(net "GND")
		)
		(pad "AW50" smd circle
			(at 10.9601 -6.02996 180)
			(size 0.450088 0.450088)
			(layers "F.Cu" "F.Mask" "F.Paste")
			(net "PVDD18_S5_P1")
		)
		(pad "AW51" smd circle
			(at 11.8999 -6.02996 180)
			(size 0.450088 0.450088)
			(layers "F.Cu" "F.Mask" "F.Paste")
			(net "GND")
		)
		(pad "AW52" smd circle
			(at 12.839954 -6.02996 180)
			(size 0.450088 0.450088)
			(layers "F.Cu" "F.Mask" "F.Paste")
			(net "PVDD18_S5_P1")
		)
		(pad "AW53" smd circle
			(at 13.780008 -6.02996 180)
			(size 0.450088 0.450088)
			(layers "F.Cu" "F.Mask" "F.Paste")
			(net "GND")
		)
		(pad "AW54" smd circle
			(at 14.720062 -6.02996 180)
			(size 0.450088 0.450088)
			(layers "F.Cu" "F.Mask" "F.Paste")
			(net "PVDD18_S5_P1")
		)
		(pad "AW55" smd circle
			(at 15.660116 -6.02996 180)
			(size 0.450088 0.450088)
			(layers "F.Cu" "F.Mask" "F.Paste")
			(net "M_C_CPU1_SA_CS_N<1>")
		)
		(pad "AW56" smd circle
			(at 16.599916 -6.02996 180)
			(size 0.450088 0.450088)
			(layers "F.Cu" "F.Mask" "F.Paste")
			(net "GND")
		)
		(pad "AW57" smd circle
			(at 17.53997 -6.02996 180)
			(size 0.450088 0.450088)
			(layers "F.Cu" "F.Mask" "F.Paste")
			(net "M_C_CPU1_SA_CA<0>")
		)
		(pad "AW58" smd circle
			(at 18.480024 -6.02996 180)
			(size 0.450088 0.450088)
			(layers "F.Cu" "F.Mask" "F.Paste")
			(net "GND")
		)
		(pad "AW59" smd circle
			(at 19.420078 -6.02996 180)
			(size 0.450088 0.450088)
			(layers "F.Cu" "F.Mask" "F.Paste")
			(net "M_D_CPU1_SA_CS_N<1>")
		)
		(pad "AW60" smd circle
			(at 20.359878 -6.02996 180)
			(size 0.450088 0.450088)
			(layers "F.Cu" "F.Mask" "F.Paste")
			(net "M_D_CPU1_SA_CA<0>")
		)
		(pad "AW61" smd circle
			(at 21.299932 -6.02996 180)
			(size 0.450088 0.450088)
			(layers "F.Cu" "F.Mask" "F.Paste")
			(net "GND")
		)
		(pad "AW62" smd circle
			(at 22.239986 -6.02996 180)
			(size 0.450088 0.450088)
			(layers "F.Cu" "F.Mask" "F.Paste")
			(net "M_B_CPU1_SA_CS_N<1>")
		)
		(pad "AW63" smd circle
			(at 23.18004 -6.02996 180)
			(size 0.450088 0.450088)
			(layers "F.Cu" "F.Mask" "F.Paste")
			(net "GND")
		)
		(pad "AW64" smd circle
			(at 24.120094 -6.02996 180)
			(size 0.450088 0.450088)
			(layers "F.Cu" "F.Mask" "F.Paste")
			(net "M_B_CPU1_SA_CA<0>")
		)
		(pad "AW65" smd circle
			(at 25.059894 -6.02996 180)
			(size 0.450088 0.450088)
			(layers "F.Cu" "F.Mask" "F.Paste")
			(net "GND")
		)
		(pad "AW66" smd circle
			(at 25.999948 -6.02996 180)
			(size 0.450088 0.450088)
			(layers "F.Cu" "F.Mask" "F.Paste")
			(net "M_F_CPU1_SA_CS_N<1>")
		)
		(pad "AW67" smd circle
			(at 26.940002 -6.02996 180)
			(size 0.450088 0.450088)
			(layers "F.Cu" "F.Mask" "F.Paste")
			(net "M_F_CPU1_SA_CA<0>")
		)
		(pad "AW68" smd circle
			(at 27.880056 -6.02996 180)
			(size 0.450088 0.450088)
			(layers "F.Cu" "F.Mask" "F.Paste")
			(net "GND")
		)
		(pad "AW69" smd circle
			(at 28.82011 -6.02996 180)
			(size 0.450088 0.450088)
			(layers "F.Cu" "F.Mask" "F.Paste")
			(net "M_E_CPU1_SA_CS_N<1>")
		)
		(pad "AW70" smd circle
			(at 29.75991 -6.02996 180)
			(size 0.450088 0.450088)
			(layers "F.Cu" "F.Mask" "F.Paste")
			(net "GND")
		)
		(pad "AW71" smd circle
			(at 30.699964 -6.02996 180)
			(size 0.450088 0.450088)
			(layers "F.Cu" "F.Mask" "F.Paste")
			(net "M_E_CPU1_SA_CA<0>")
		)
		(pad "AW72" smd circle
			(at 31.640018 -6.02996 180)
			(size 0.450088 0.450088)
			(layers "F.Cu" "F.Mask" "F.Paste")
			(net "GND")
		)
		(pad "AW73" smd circle
			(at 32.580072 -6.02996 180)
			(size 0.450088 0.450088)
			(layers "F.Cu" "F.Mask" "F.Paste")
			(net "M_A_CPU1_SA_CS_N<1>")
		)
		(pad "AW74" smd circle
			(at 33.519872 -6.02996 180)
			(size 0.450088 0.450088)
			(layers "F.Cu" "F.Mask" "F.Paste")
			(net "M_A_CPU1_SA_CA<0>")
		)
		(pad "AW75" smd circle
			(at 34.459926 -6.02996 180)
			(size 0.450088 0.450088)
			(layers "F.Cu" "F.Mask" "F.Paste")
			(net "GND")
		)
		(pad "AY2" smd circle
			(at -33.690052 -5.219954 180)
			(size 0.450088 0.450088)
			(layers "F.Cu" "F.Mask" "F.Paste")
			(net "M_G_CPU1_SA_CA<1>")
		)
		(pad "AY3" smd circle
			(at -32.749998 -5.219954 180)
			(size 0.450088 0.450088)
			(layers "F.Cu" "F.Mask" "F.Paste")
			(net "GND")
		)
		(pad "AY4" smd circle
			(at -31.809944 -5.219954 180)
			(size 0.450088 0.450088)
			(layers "F.Cu" "F.Mask" "F.Paste")
			(net "M_G_CPU1_SA_CA<2>")
		)
		(pad "AY5" smd circle
			(at -30.86989 -5.219954 180)
			(size 0.450088 0.450088)
			(layers "F.Cu" "F.Mask" "F.Paste")
			(net "GND")
		)
		(pad "AY6" smd circle
			(at -29.93009 -5.219954 180)
			(size 0.450088 0.450088)
			(layers "F.Cu" "F.Mask" "F.Paste")
			(net "M_K_CPU1_SA_CA<1>")
		)
		(pad "AY7" smd circle
			(at -28.990036 -5.219954 180)
			(size 0.450088 0.450088)
			(layers "F.Cu" "F.Mask" "F.Paste")
			(net "M_K_CPU1_SA_CA<2>")
		)
		(pad "AY8" smd circle
			(at -28.049982 -5.219954 180)
			(size 0.450088 0.450088)
			(layers "F.Cu" "F.Mask" "F.Paste")
			(net "GND")
		)
		(pad "AY9" smd circle
			(at -27.109928 -5.219954 180)
			(size 0.450088 0.450088)
			(layers "F.Cu" "F.Mask" "F.Paste")
			(net "M_L_CPU1_SA_CA<1>")
		)
		(pad "AY10" smd circle
			(at -26.170128 -5.219954 180)
			(size 0.450088 0.450088)
			(layers "F.Cu" "F.Mask" "F.Paste")
			(net "GND")
		)
		(pad "AY11" smd circle
			(at -25.230074 -5.219954 180)
			(size 0.450088 0.450088)
			(layers "F.Cu" "F.Mask" "F.Paste")
			(net "M_L_CPU1_SA_CA<2>")
		)
		(pad "AY12" smd circle
			(at -24.29002 -5.219954 180)
			(size 0.450088 0.450088)
			(layers "F.Cu" "F.Mask" "F.Paste")
			(net "GND")
		)
		(pad "AY13" smd circle
			(at -23.349966 -5.219954 180)
			(size 0.450088 0.450088)
			(layers "F.Cu" "F.Mask" "F.Paste")
			(net "M_H_CPU1_SA_CA<1>")
		)
	)
)
